FILE_TYPE = CONNECTIVITY;
{Allegro Design Entry HDL 17.4-2019 S026 (4007227) 1/17/2022}
"PAGE_NUMBER" = 87;
0"NC";
1"GND\g";
2"GND\g";
3"P3V3\g";
4"M_C_CPU0_SA_DQ<31:0>";
5"M_C_CPU0_SA_CB<7:0>";
6"M_C_CPU0_SB_CB<7:0>";
7"M_C_CPU0_SA_CA<6:0>";
8"M_C_CPU0_SB_CA<6:0>";
9"M_C_CPU0_SB_DQ<31:0>";
10"M_C_CPU0_SA_DQS_DN<9:0>";
11"M_C_CPU0_SA_DQS_DP<9:0>";
12"M_C_CPU0_SB_DQS_DP<9:0>";
13"M_C_CPU0_SB_DQS_DN<9:0>";
14"M_C_CPU0_ALERT_N";
15"I3C_SPD_DDRAF_CPU0_SDA";
16"I3C_SPD_DDRAF_CPU0_SCL";
17"M_C_CPU0_RESET_N";
18"P12V_MEM_CPU0\g";
19"GND\g";
20"GND\g";
21"GND\g";
22"I3C_SPD_DDRC_CPU0_SCL";
23"PWRGD_CHC_CPU0_DIMM";
24"PWRGD_CHAF_CPU0";
25"M_C_CPU0_SA_RSP<0>";
26"M_C_CPU0_SB_RSP<0>";
27"M_C_CPU0_SB_DQ<0>";
28"M_C_CPU0_SA_DQ<1>";
29"PD_CHC_CPU0_DIMM_SAA";
30"M_C_CPU0_SB_DQS_DP<9>";
31"M_C_CPU0_SB_DQS_DN<9>";
32"M_C_CPU0_SA_DQS_DP<9>";
33"M_C_CPU0_SA_DQS_DN<9>";
34"M_C_CPU0_SA_DQS_DP<8>";
35"M_C_CPU0_SA_DQS_DN<8>";
36"M_C_CPU0_SB_DQS_DN<7>";
37"M_C_CPU0_SA_DQS_DP<7>";
38"M_C_CPU0_SB_DQS_DP<6>";
39"M_C_CPU0_SB_DQS_DN<6>";
40"M_C_CPU0_SA_DQS_DN<6>";
41"M_C_CPU0_SB_DQS_DP<5>";
42"M_C_CPU0_SB_DQS_DN<5>";
43"M_C_CPU0_SA_DQS_DP<5>";
44"M_C_CPU0_SA_DQS_DN<5>";
45"M_C_CPU0_SB_DQS_DP<4>";
46"M_C_CPU0_SB_DQS_DN<4>";
47"M_C_CPU0_SA_DQS_DP<4>";
48"M_C_CPU0_SA_DQS_DN<4>";
49"M_C_CPU0_SB_DQS_DP<3>";
50"M_C_CPU0_SB_DQS_DN<3>";
51"M_C_CPU0_SA_DQS_DP<3>";
52"M_C_CPU0_SA_DQS_DN<3>";
53"M_C_CPU0_SB_DQS_DP<2>";
54"M_C_CPU0_SB_DQS_DN<2>";
55"M_C_CPU0_SA_DQS_DP<2>";
56"M_C_CPU0_SA_DQS_DN<2>";
57"M_C_CPU0_SB_DQS_DP<1>";
58"M_C_CPU0_SB_DQS_DN<1>";
59"M_C_CPU0_SA_DQS_DP<1>";
60"M_C_CPU0_SA_DQS_DN<1>";
61"M_C_CPU0_SB_DQS_DP<0>";
62"M_C_CPU0_SB_DQS_DN<0>";
63"M_C_CPU0_SA_DQS_DP<0>";
64"M_C_CPU0_SA_DQS_DN<0>";
65"M_C_CPU0_SB_DQS_DP<7>";
66"M_C_CPU0_SB_DQS_DN<8>";
67"M_C_CPU0_SB_DQS_DP<8>";
68"M_C_CPU0_SA_DQS_DP<6>";
69"M_C_CPU0_SA_DQS_DN<7>";
70"M_C_CPU0_SA_DQ<20>";
71"M_C_CPU0_SA_DQ<21>";
72"M_C_CPU0_SA_DQ<22>";
73"M_C_CPU0_SA_DQ<23>";
74"M_C_CPU0_SA_DQ<24>";
75"M_C_CPU0_SA_DQ<27>";
76"M_C_CPU0_SA_DQ<28>";
77"M_C_CPU0_SB_PAR";
78"M_C_CPU0_SA_PAR";
79"M_C_CPU0_SB_DQ<1>";
80"M_C_CPU0_SB_DQ<2>";
81"M_C_CPU0_SB_DQ<3>";
82"M_C_CPU0_SB_DQ<4>";
83"M_C_CPU0_SB_DQ<5>";
84"M_C_CPU0_SB_DQ<6>";
85"M_C_CPU0_SB_DQ<7>";
86"M_C_CPU0_SB_DQ<8>";
87"M_C_CPU0_SB_DQ<9>";
88"M_C_CPU0_SB_DQ<10>";
89"M_C_CPU0_SB_DQ<11>";
90"M_C_CPU0_SB_DQ<12>";
91"M_C_CPU0_SB_DQ<13>";
92"M_C_CPU0_SB_DQ<14>";
93"M_C_CPU0_SB_DQ<15>";
94"M_C_CPU0_SB_DQ<16>";
95"M_C_CPU0_SB_DQ<17>";
96"M_C_CPU0_SB_DQ<18>";
97"M_C_CPU0_SB_DQ<19>";
98"M_C_CPU0_SB_DQ<20>";
99"M_C_CPU0_SB_DQ<21>";
100"M_C_CPU0_SB_DQ<22>";
101"M_C_CPU0_SB_DQ<23>";
102"M_C_CPU0_SB_DQ<24>";
103"M_C_CPU0_SB_DQ<25>";
104"M_C_CPU0_SB_DQ<26>";
105"M_C_CPU0_SB_DQ<27>";
106"M_C_CPU0_SB_DQ<28>";
107"M_C_CPU0_SB_DQ<29>";
108"M_C_CPU0_SB_DQ<30>";
109"M_C_CPU0_SB_DQ<31>";
110"M_C_CPU0_SA_DQ<0>";
111"M_C_CPU0_SA_DQ<2>";
112"M_C_CPU0_SA_DQ<3>";
113"M_C_CPU0_SA_DQ<4>";
114"M_C_CPU0_SA_DQ<5>";
115"M_C_CPU0_SA_DQ<6>";
116"M_C_CPU0_SA_DQ<7>";
117"M_C_CPU0_SA_DQ<8>";
118"M_C_CPU0_SA_DQ<9>";
119"M_C_CPU0_SA_DQ<10>";
120"M_C_CPU0_SA_DQ<11>";
121"M_C_CPU0_SA_DQ<12>";
122"M_C_CPU0_SA_DQ<13>";
123"M_C_CPU0_SA_DQ<14>";
124"M_C_CPU0_SA_DQ<15>";
125"M_C_CPU0_SA_DQ<16>";
126"M_C_CPU0_SA_DQ<17>";
127"M_C_CPU0_SA_DQ<18>";
128"M_C_CPU0_SA_DQ<19>";
129"M_C_CPU0_SA_DQ<25>";
130"M_C_CPU0_SA_DQ<26>";
131"M_C_CPU0_SA_DQ<29>";
132"M_C_CPU0_SA_DQ<30>";
133"M_C_CPU0_SB_CS_N<1>";
134"M_C_CPU0_SA_CS_N<1>";
135"M_C_CPU0_SB_CS_N<0>";
136"M_C_CPU0_SA_CS_N<0>";
137"M_C_CPU0_CLK_DP<0>";
138"M_C_CPU0_CLK_DN<0>";
139"M_C_CPU0_SB_CB<0>";
140"M_C_CPU0_SB_CB<1>";
141"M_C_CPU0_SB_CB<2>";
142"M_C_CPU0_SB_CB<3>";
143"M_C_CPU0_SB_CB<4>";
144"M_C_CPU0_SB_CB<5>";
145"M_C_CPU0_SB_CB<6>";
146"M_C_CPU0_SA_CB<0>";
147"M_C_CPU0_SA_CB<2>";
148"M_C_CPU0_SA_CB<3>";
149"M_C_CPU0_SA_CB<5>";
150"M_C_CPU0_SA_CB<6>";
151"M_C_CPU0_SB_CA<6>";
152"M_C_CPU0_SA_CA<6>";
153"M_C_CPU0_SB_CA<5>";
154"M_C_CPU0_SA_CA<5>";
155"M_C_CPU0_SB_CA<4>";
156"M_C_CPU0_SA_CA<4>";
157"M_C_CPU0_SB_CA<3>";
158"M_C_CPU0_SA_CA<3>";
159"M_C_CPU0_SB_CA<2>";
160"M_C_CPU0_SA_CA<2>";
161"M_C_CPU0_SB_CA<1>";
162"M_C_CPU0_SA_CA<1>";
163"M_C_CPU0_SB_CA<0>";
164"M_C_CPU0_SA_CA<0>";
165"M_C_CPU0_SB_CB<7>";
166"M_C_CPU0_SA_CB<1>";
167"M_C_CPU0_SA_CB<4>";
168"M_C_CPU0_SA_CB<7>";
169"M_C_CPU0_SA_DQ<31>";
170"I3C_SPD_DDRC_CPU0_SDA";
171"PD_CHC_CPU0_DIMM_SAA";
172"P3V3_AUX\g";
%"GND"
"1","(-2300,2300)","0","mstr_symbols","I150";
;
SIZE"1B"
CDS_LIB"mstr_symbols"
VOLTAGE"0.0"
BODY_TYPE"PLUMBING"
HDL_POWER"GND";
"A\NAC"21;
%"GND"
"1","(-500,2100)","0","mstr_symbols","I152";
;
CDS_LIB"mstr_symbols"
SIZE"1B"
VOLTAGE"0.0"
BODY_TYPE"PLUMBING"
HDL_POWER"GND";
"A\NAC"20;
%"VCC_CORE"
"1","(-8800,3775)","0","mstr_symbols","I177";
;
HDL_POWER"P3V3_AUX"
CDS_LIB"mstr_symbols"
VOLTAGE"3.3"
ROOM"PVCCINFAON_CPU0_CTRL";
"A"172;
%"TAP"
"1","(-7925,3575)","2","mstr_standard","I187";
;
CDS_LIB"mstr_standard"
BODY_TYPE"PLUMBING"
HDL_TAP"TRUE";
"B \NAC \NWC"6;
"S \NAC"
BN"1"140;
%"TAP"
"1","(-7925,3625)","2","mstr_standard","I188";
;
CDS_LIB"mstr_standard"
BODY_TYPE"PLUMBING"
HDL_TAP"TRUE";
"B \NAC \NWC"6;
"S \NAC"
BN"2"141;
%"TAP"
"1","(-7925,3525)","2","mstr_standard","I189";
;
CDS_LIB"mstr_standard"
BODY_TYPE"PLUMBING"
HDL_TAP"TRUE";
"B \NAC \NWC"6;
"S \NAC"
BN"0"139;
%"TAP"
"1","(-7925,3675)","2","mstr_standard","I190";
;
CDS_LIB"mstr_standard"
BODY_TYPE"PLUMBING"
HDL_TAP"TRUE";
"B \NAC \NWC"6;
"S \NAC"
BN"3"142;
%"TAP"
"1","(-7925,3725)","2","mstr_standard","I191";
;
CDS_LIB"mstr_standard"
BODY_TYPE"PLUMBING"
HDL_TAP"TRUE";
"B \NAC \NWC"6;
"S \NAC"
BN"4"143;
%"TAP"
"1","(-7925,3775)","2","mstr_standard","I192";
;
CDS_LIB"mstr_standard"
BODY_TYPE"PLUMBING"
HDL_TAP"TRUE";
"B \NAC \NWC"6;
"S \NAC"
BN"5"144;
%"TAP"
"1","(-7925,3875)","2","mstr_standard","I193";
;
CDS_LIB"mstr_standard"
BODY_TYPE"PLUMBING"
HDL_TAP"TRUE";
"B \NAC \NWC"6;
"S \NAC"
BN"7"165;
%"TAP"
"1","(-7925,3825)","2","mstr_standard","I194";
;
CDS_LIB"mstr_standard"
BODY_TYPE"PLUMBING"
HDL_TAP"TRUE";
"B \NAC \NWC"6;
"S \NAC"
BN"6"145;
%"TAP"
"1","(-7925,4075)","2","mstr_standard","I195";
;
CDS_LIB"mstr_standard"
BODY_TYPE"PLUMBING"
HDL_TAP"TRUE";
"B \NAC \NWC"5;
"S \NAC"
BN"2"147;
%"TAP"
"1","(-7925,4025)","2","mstr_standard","I196";
;
CDS_LIB"mstr_standard"
BODY_TYPE"PLUMBING"
HDL_TAP"TRUE";
"B \NAC \NWC"5;
"S \NAC"
BN"1"166;
%"TAP"
"1","(-7925,3975)","2","mstr_standard","I197";
;
CDS_LIB"mstr_standard"
BODY_TYPE"PLUMBING"
HDL_TAP"TRUE";
"B \NAC \NWC"5;
"S \NAC"
BN"0"146;
%"TAP"
"1","(-7925,4125)","2","mstr_standard","I198";
;
CDS_LIB"mstr_standard"
BODY_TYPE"PLUMBING"
HDL_TAP"TRUE";
"B \NAC \NWC"5;
"S \NAC"
BN"3"148;
%"TAP"
"1","(-7925,4175)","2","mstr_standard","I199";
;
CDS_LIB"mstr_standard"
BODY_TYPE"PLUMBING"
HDL_TAP"TRUE";
"B \NAC \NWC"5;
"S \NAC"
BN"4"167;
%"TAP"
"1","(-7925,4225)","2","mstr_standard","I200";
;
CDS_LIB"mstr_standard"
BODY_TYPE"PLUMBING"
HDL_TAP"TRUE";
"B \NAC \NWC"5;
"S \NAC"
BN"5"149;
%"TAP"
"1","(-7925,4275)","2","mstr_standard","I201";
;
CDS_LIB"mstr_standard"
BODY_TYPE"PLUMBING"
HDL_TAP"TRUE";
"B \NAC \NWC"5;
"S \NAC"
BN"6"150;
%"TAP"
"1","(-7925,4325)","2","mstr_standard","I202";
;
CDS_LIB"mstr_standard"
BODY_TYPE"PLUMBING"
HDL_TAP"TRUE";
"B \NAC \NWC"5;
"S \NAC"
BN"7"168;
%"TAP"
"1","(-7925,5175)","2","mstr_standard","I203";
;
CDS_LIB"mstr_standard"
BODY_TYPE"PLUMBING"
HDL_TAP"TRUE";
"B \NAC \NWC"8;
"S \NAC"
BN"3"157;
%"TAP"
"1","(-7925,5075)","2","mstr_standard","I204";
;
CDS_LIB"mstr_standard"
BODY_TYPE"PLUMBING"
HDL_TAP"TRUE";
"B \NAC \NWC"8;
"S \NAC"
BN"1"161;
%"TAP"
"1","(-7925,5025)","2","mstr_standard","I205";
;
CDS_LIB"mstr_standard"
BODY_TYPE"PLUMBING"
HDL_TAP"TRUE";
"B \NAC \NWC"8;
"S \NAC"
BN"0"163;
%"TAP"
"1","(-7925,5125)","2","mstr_standard","I206";
;
CDS_LIB"mstr_standard"
BODY_TYPE"PLUMBING"
HDL_TAP"TRUE";
"B \NAC \NWC"8;
"S \NAC"
BN"2"159;
%"TAP"
"1","(-6225,2575)","0","mstr_standard","I207";
;
CDS_LIB"mstr_standard"
BODY_TYPE"PLUMBING"
HDL_TAP"TRUE";
"B \NAC \NWC"9;
"S \NAC"
BN"1"79;
%"TAP"
"1","(-6225,2525)","0","mstr_standard","I208";
;
CDS_LIB"mstr_standard"
BODY_TYPE"PLUMBING"
HDL_TAP"TRUE";
"B \NAC \NWC"9;
"S \NAC"
BN"0"27;
%"TAP"
"1","(-6225,2625)","0","mstr_standard","I209";
;
CDS_LIB"mstr_standard"
BODY_TYPE"PLUMBING"
HDL_TAP"TRUE";
"B \NAC \NWC"9;
"S \NAC"
BN"2"80;
%"TAP"
"1","(-6225,2675)","0","mstr_standard","I210";
;
CDS_LIB"mstr_standard"
BODY_TYPE"PLUMBING"
HDL_TAP"TRUE";
"B \NAC \NWC"9;
"S \NAC"
BN"3"81;
%"TAP"
"1","(-6225,2725)","0","mstr_standard","I211";
;
CDS_LIB"mstr_standard"
BODY_TYPE"PLUMBING"
HDL_TAP"TRUE";
"B \NAC \NWC"9;
"S \NAC"
BN"4"82;
%"TAP"
"1","(-6225,2775)","0","mstr_standard","I212";
;
CDS_LIB"mstr_standard"
BODY_TYPE"PLUMBING"
HDL_TAP"TRUE";
"B \NAC \NWC"9;
"S \NAC"
BN"5"83;
%"TAP"
"1","(-6225,2875)","0","mstr_standard","I213";
;
CDS_LIB"mstr_standard"
BODY_TYPE"PLUMBING"
HDL_TAP"TRUE";
"B \NAC \NWC"9;
"S \NAC"
BN"7"85;
%"TAP"
"1","(-6225,2825)","0","mstr_standard","I214";
;
CDS_LIB"mstr_standard"
BODY_TYPE"PLUMBING"
HDL_TAP"TRUE";
"B \NAC \NWC"9;
"S \NAC"
BN"6"84;
%"TAP"
"1","(-6225,2925)","0","mstr_standard","I215";
;
CDS_LIB"mstr_standard"
BODY_TYPE"PLUMBING"
HDL_TAP"TRUE";
"B \NAC \NWC"9;
"S \NAC"
BN"8"86;
%"TAP"
"1","(-6225,2975)","0","mstr_standard","I216";
;
CDS_LIB"mstr_standard"
BODY_TYPE"PLUMBING"
HDL_TAP"TRUE";
"B \NAC \NWC"9;
"S \NAC"
BN"9"87;
%"TAP"
"1","(-6225,3025)","0","mstr_standard","I217";
;
CDS_LIB"mstr_standard"
BODY_TYPE"PLUMBING"
HDL_TAP"TRUE";
"B \NAC \NWC"9;
"S \NAC"
BN"10"88;
%"TAP"
"1","(-6225,3075)","0","mstr_standard","I218";
;
CDS_LIB"mstr_standard"
BODY_TYPE"PLUMBING"
HDL_TAP"TRUE";
"B \NAC \NWC"9;
"S \NAC"
BN"11"89;
%"TAP"
"1","(-6225,3125)","0","mstr_standard","I219";
;
CDS_LIB"mstr_standard"
BODY_TYPE"PLUMBING"
HDL_TAP"TRUE";
"B \NAC \NWC"9;
"S \NAC"
BN"12"90;
%"TAP"
"1","(-6225,3175)","0","mstr_standard","I220";
;
CDS_LIB"mstr_standard"
BODY_TYPE"PLUMBING"
HDL_TAP"TRUE";
"B \NAC \NWC"9;
"S \NAC"
BN"13"91;
%"TAP"
"1","(-6225,3275)","0","mstr_standard","I221";
;
CDS_LIB"mstr_standard"
BODY_TYPE"PLUMBING"
HDL_TAP"TRUE";
"B \NAC \NWC"9;
"S \NAC"
BN"15"93;
%"TAP"
"1","(-6225,3225)","0","mstr_standard","I222";
;
CDS_LIB"mstr_standard"
BODY_TYPE"PLUMBING"
HDL_TAP"TRUE";
"B \NAC \NWC"9;
"S \NAC"
BN"14"92;
%"TAP"
"1","(-6225,3425)","0","mstr_standard","I223";
;
CDS_LIB"mstr_standard"
BODY_TYPE"PLUMBING"
HDL_TAP"TRUE";
"B \NAC \NWC"9;
"S \NAC"
BN"18"96;
%"TAP"
"1","(-6225,3375)","0","mstr_standard","I224";
;
CDS_LIB"mstr_standard"
BODY_TYPE"PLUMBING"
HDL_TAP"TRUE";
"B \NAC \NWC"9;
"S \NAC"
BN"17"95;
%"TAP"
"1","(-6225,3325)","0","mstr_standard","I225";
;
CDS_LIB"mstr_standard"
BODY_TYPE"PLUMBING"
HDL_TAP"TRUE";
"B \NAC \NWC"9;
"S \NAC"
BN"16"94;
%"TAP"
"1","(-6225,3575)","0","mstr_standard","I226";
;
CDS_LIB"mstr_standard"
BODY_TYPE"PLUMBING"
HDL_TAP"TRUE";
"B \NAC \NWC"9;
"S \NAC"
BN"21"99;
%"TAP"
"1","(-6225,3625)","0","mstr_standard","I227";
;
CDS_LIB"mstr_standard"
BODY_TYPE"PLUMBING"
HDL_TAP"TRUE";
"B \NAC \NWC"9;
"S \NAC"
BN"22"100;
%"TAP"
"1","(-6225,3525)","0","mstr_standard","I228";
;
CDS_LIB"mstr_standard"
BODY_TYPE"PLUMBING"
HDL_TAP"TRUE";
"B \NAC \NWC"9;
"S \NAC"
BN"20"98;
%"TAP"
"1","(-6225,3675)","0","mstr_standard","I229";
;
CDS_LIB"mstr_standard"
BODY_TYPE"PLUMBING"
HDL_TAP"TRUE";
"B \NAC \NWC"9;
"S \NAC"
BN"23"101;
%"TAP"
"1","(-6225,3475)","0","mstr_standard","I230";
;
CDS_LIB"mstr_standard"
BODY_TYPE"PLUMBING"
HDL_TAP"TRUE";
"B \NAC \NWC"9;
"S \NAC"
BN"19"97;
%"TAP"
"1","(-6225,3825)","0","mstr_standard","I231";
;
CDS_LIB"mstr_standard"
BODY_TYPE"PLUMBING"
HDL_TAP"TRUE";
"B \NAC \NWC"9;
"S \NAC"
BN"26"104;
%"TAP"
"1","(-6225,3875)","0","mstr_standard","I232";
;
CDS_LIB"mstr_standard"
BODY_TYPE"PLUMBING"
HDL_TAP"TRUE";
"B \NAC \NWC"9;
"S \NAC"
BN"27"105;
%"TAP"
"1","(-6225,3775)","0","mstr_standard","I233";
;
CDS_LIB"mstr_standard"
BODY_TYPE"PLUMBING"
HDL_TAP"TRUE";
"B \NAC \NWC"9;
"S \NAC"
BN"25"103;
%"TAP"
"1","(-6225,3925)","0","mstr_standard","I234";
;
CDS_LIB"mstr_standard"
BODY_TYPE"PLUMBING"
HDL_TAP"TRUE";
"B \NAC \NWC"9;
"S \NAC"
BN"28"106;
%"TAP"
"1","(-6225,3725)","0","mstr_standard","I235";
;
CDS_LIB"mstr_standard"
BODY_TYPE"PLUMBING"
HDL_TAP"TRUE";
"B \NAC \NWC"9;
"S \NAC"
BN"24"102;
%"TAP"
"1","(-6225,4175)","0","mstr_standard","I236";
;
CDS_LIB"mstr_standard"
BODY_TYPE"PLUMBING"
HDL_TAP"TRUE";
"B \NAC \NWC"4;
"S \NAC"
BN"0"110;
%"TAP"
"1","(-6225,4025)","0","mstr_standard","I237";
;
CDS_LIB"mstr_standard"
BODY_TYPE"PLUMBING"
HDL_TAP"TRUE";
"B \NAC \NWC"9;
"S \NAC"
BN"30"108;
%"TAP"
"1","(-6225,4075)","0","mstr_standard","I238";
;
CDS_LIB"mstr_standard"
BODY_TYPE"PLUMBING"
HDL_TAP"TRUE";
"B \NAC \NWC"9;
"S \NAC"
BN"31"109;
%"TAP"
"1","(-6225,3975)","0","mstr_standard","I239";
;
CDS_LIB"mstr_standard"
BODY_TYPE"PLUMBING"
HDL_TAP"TRUE";
"B \NAC \NWC"9;
"S \NAC"
BN"29"107;
%"TAP"
"1","(-6225,4275)","0","mstr_standard","I240";
;
CDS_LIB"mstr_standard"
BODY_TYPE"PLUMBING"
HDL_TAP"TRUE";
"B \NAC \NWC"4;
"S \NAC"
BN"2"111;
%"TAP"
"1","(-6225,4225)","0","mstr_standard","I241";
;
CDS_LIB"mstr_standard"
BODY_TYPE"PLUMBING"
HDL_TAP"TRUE";
"B \NAC \NWC"4;
"S \NAC"
BN"1"28;
%"TAP"
"1","(-6225,4325)","0","mstr_standard","I242";
;
CDS_LIB"mstr_standard"
BODY_TYPE"PLUMBING"
HDL_TAP"TRUE";
"B \NAC \NWC"4;
"S \NAC"
BN"3"112;
%"TAP"
"1","(-6225,4375)","0","mstr_standard","I243";
;
CDS_LIB"mstr_standard"
BODY_TYPE"PLUMBING"
HDL_TAP"TRUE";
"B \NAC \NWC"4;
"S \NAC"
BN"4"113;
%"TAP"
"1","(-6225,4425)","0","mstr_standard","I244";
;
CDS_LIB"mstr_standard"
BODY_TYPE"PLUMBING"
HDL_TAP"TRUE";
"B \NAC \NWC"4;
"S \NAC"
BN"5"114;
%"TAP"
"1","(-6225,4525)","0","mstr_standard","I245";
;
CDS_LIB"mstr_standard"
BODY_TYPE"PLUMBING"
HDL_TAP"TRUE";
"B \NAC \NWC"4;
"S \NAC"
BN"7"116;
%"TAP"
"1","(-6225,4475)","0","mstr_standard","I246";
;
CDS_LIB"mstr_standard"
BODY_TYPE"PLUMBING"
HDL_TAP"TRUE";
"B \NAC \NWC"4;
"S \NAC"
BN"6"115;
%"TAP"
"1","(-6225,4575)","0","mstr_standard","I247";
;
CDS_LIB"mstr_standard"
BODY_TYPE"PLUMBING"
HDL_TAP"TRUE";
"B \NAC \NWC"4;
"S \NAC"
BN"8"117;
%"TAP"
"1","(-6225,4625)","0","mstr_standard","I248";
;
CDS_LIB"mstr_standard"
BODY_TYPE"PLUMBING"
HDL_TAP"TRUE";
"B \NAC \NWC"4;
"S \NAC"
BN"9"118;
%"TAP"
"1","(-6225,4675)","0","mstr_standard","I249";
;
CDS_LIB"mstr_standard"
BODY_TYPE"PLUMBING"
HDL_TAP"TRUE";
"B \NAC \NWC"4;
"S \NAC"
BN"10"119;
%"TAP"
"1","(-6225,4875)","0","mstr_standard","I250";
;
CDS_LIB"mstr_standard"
BODY_TYPE"PLUMBING"
HDL_TAP"TRUE";
"B \NAC \NWC"4;
"S \NAC"
BN"14"123;
%"TAP"
"1","(-6225,4925)","0","mstr_standard","I251";
;
CDS_LIB"mstr_standard"
BODY_TYPE"PLUMBING"
HDL_TAP"TRUE";
"B \NAC \NWC"4;
"S \NAC"
BN"15"124;
%"TAP"
"1","(-6225,4825)","0","mstr_standard","I252";
;
CDS_LIB"mstr_standard"
BODY_TYPE"PLUMBING"
HDL_TAP"TRUE";
"B \NAC \NWC"4;
"S \NAC"
BN"13"122;
%"TAP"
"1","(-6225,4775)","0","mstr_standard","I253";
;
CDS_LIB"mstr_standard"
BODY_TYPE"PLUMBING"
HDL_TAP"TRUE";
"B \NAC \NWC"4;
"S \NAC"
BN"12"121;
%"TAP"
"1","(-6225,4725)","0","mstr_standard","I254";
;
CDS_LIB"mstr_standard"
BODY_TYPE"PLUMBING"
HDL_TAP"TRUE";
"B \NAC \NWC"4;
"S \NAC"
BN"11"120;
%"TAP"
"1","(-6225,5025)","0","mstr_standard","I255";
;
CDS_LIB"mstr_standard"
BODY_TYPE"PLUMBING"
HDL_TAP"TRUE";
"B \NAC \NWC"4;
"S \NAC"
BN"17"126;
%"TAP"
"1","(-6225,5075)","0","mstr_standard","I256";
;
CDS_LIB"mstr_standard"
BODY_TYPE"PLUMBING"
HDL_TAP"TRUE";
"B \NAC \NWC"4;
"S \NAC"
BN"18"127;
%"TAP"
"1","(-6225,4975)","0","mstr_standard","I257";
;
CDS_LIB"mstr_standard"
BODY_TYPE"PLUMBING"
HDL_TAP"TRUE";
"B \NAC \NWC"4;
"S \NAC"
BN"16"125;
%"TAP"
"1","(-6225,5175)","0","mstr_standard","I258";
;
CDS_LIB"mstr_standard"
BODY_TYPE"PLUMBING"
HDL_TAP"TRUE";
"B \NAC \NWC"4;
"S \NAC"
BN"20"70;
%"TAP"
"1","(-6225,5125)","0","mstr_standard","I259";
;
CDS_LIB"mstr_standard"
BODY_TYPE"PLUMBING"
HDL_TAP"TRUE";
"B \NAC \NWC"4;
"S \NAC"
BN"19"128;
%"TAP"
"1","(-7925,5325)","2","mstr_standard","I263";
;
CDS_LIB"mstr_standard"
BODY_TYPE"PLUMBING"
HDL_TAP"TRUE";
"B \NAC \NWC"8;
"S \NAC"
BN"6"151;
%"TAP"
"1","(-7925,5225)","2","mstr_standard","I264";
;
CDS_LIB"mstr_standard"
BODY_TYPE"PLUMBING"
HDL_TAP"TRUE";
"B \NAC \NWC"8;
"S \NAC"
BN"4"155;
%"TAP"
"1","(-7925,5275)","2","mstr_standard","I265";
;
CDS_LIB"mstr_standard"
BODY_TYPE"PLUMBING"
HDL_TAP"TRUE";
"B \NAC \NWC"8;
"S \NAC"
BN"5"153;
%"TAP"
"1","(-7925,5425)","2","mstr_standard","I266";
;
CDS_LIB"mstr_standard"
BODY_TYPE"PLUMBING"
HDL_TAP"TRUE";
"B \NAC \NWC"7;
"S \NAC"
BN"0"164;
%"TAP"
"1","(-7925,5475)","2","mstr_standard","I267";
;
CDS_LIB"mstr_standard"
BODY_TYPE"PLUMBING"
HDL_TAP"TRUE";
"B \NAC \NWC"7;
"S \NAC"
BN"1"162;
%"TAP"
"1","(-7925,5525)","2","mstr_standard","I268";
;
CDS_LIB"mstr_standard"
BODY_TYPE"PLUMBING"
HDL_TAP"TRUE";
"B \NAC \NWC"7;
"S \NAC"
BN"2"160;
%"TAP"
"1","(-7925,5575)","2","mstr_standard","I269";
;
CDS_LIB"mstr_standard"
BODY_TYPE"PLUMBING"
HDL_TAP"TRUE";
"B \NAC \NWC"7;
"S \NAC"
BN"3"158;
%"TAP"
"1","(-7925,5675)","2","mstr_standard","I270";
;
CDS_LIB"mstr_standard"
BODY_TYPE"PLUMBING"
HDL_TAP"TRUE";
"B \NAC \NWC"7;
"S \NAC"
BN"5"154;
%"TAP"
"1","(-7925,5625)","2","mstr_standard","I271";
;
CDS_LIB"mstr_standard"
BODY_TYPE"PLUMBING"
HDL_TAP"TRUE";
"B \NAC \NWC"7;
"S \NAC"
BN"4"156;
%"TAP"
"1","(-7925,5725)","2","mstr_standard","I272";
;
CDS_LIB"mstr_standard"
BODY_TYPE"PLUMBING"
HDL_TAP"TRUE";
"B \NAC \NWC"7;
"S \NAC"
BN"6"152;
%"TAP"
"1","(-6225,5325)","0","mstr_standard","I273";
;
CDS_LIB"mstr_standard"
BODY_TYPE"PLUMBING"
HDL_TAP"TRUE";
"B \NAC \NWC"4;
"S \NAC"
BN"23"73;
%"TAP"
"1","(-6225,5225)","0","mstr_standard","I274";
;
CDS_LIB"mstr_standard"
BODY_TYPE"PLUMBING"
HDL_TAP"TRUE";
"B \NAC \NWC"4;
"S \NAC"
BN"21"71;
%"TAP"
"1","(-6225,5275)","0","mstr_standard","I275";
;
CDS_LIB"mstr_standard"
BODY_TYPE"PLUMBING"
HDL_TAP"TRUE";
"B \NAC \NWC"4;
"S \NAC"
BN"22"72;
%"TAP"
"1","(-6225,5375)","0","mstr_standard","I276";
;
CDS_LIB"mstr_standard"
BODY_TYPE"PLUMBING"
HDL_TAP"TRUE";
"B \NAC \NWC"4;
"S \NAC"
BN"24"74;
%"TAP"
"1","(-6225,5425)","0","mstr_standard","I277";
;
CDS_LIB"mstr_standard"
BODY_TYPE"PLUMBING"
HDL_TAP"TRUE";
"B \NAC \NWC"4;
"S \NAC"
BN"25"129;
%"TAP"
"1","(-6225,5475)","0","mstr_standard","I278";
;
CDS_LIB"mstr_standard"
BODY_TYPE"PLUMBING"
HDL_TAP"TRUE";
"B \NAC \NWC"4;
"S \NAC"
BN"26"130;
%"TAP"
"1","(-6225,5725)","0","mstr_standard","I279";
;
CDS_LIB"mstr_standard"
BODY_TYPE"PLUMBING"
HDL_TAP"TRUE";
"B \NAC \NWC"4;
"S \NAC"
BN"31"169;
%"TAP"
"1","(-6225,5525)","0","mstr_standard","I280";
;
CDS_LIB"mstr_standard"
BODY_TYPE"PLUMBING"
HDL_TAP"TRUE";
"B \NAC \NWC"4;
"S \NAC"
BN"27"75;
%"TAP"
"1","(-6225,5575)","0","mstr_standard","I281";
;
CDS_LIB"mstr_standard"
BODY_TYPE"PLUMBING"
HDL_TAP"TRUE";
"B \NAC \NWC"4;
"S \NAC"
BN"28"76;
%"TAP"
"1","(-6225,5675)","0","mstr_standard","I282";
;
CDS_LIB"mstr_standard"
BODY_TYPE"PLUMBING"
HDL_TAP"TRUE";
"B \NAC \NWC"4;
"S \NAC"
BN"30"132;
%"TAP"
"1","(-6225,5625)","0","mstr_standard","I283";
;
CDS_LIB"mstr_standard"
BODY_TYPE"PLUMBING"
HDL_TAP"TRUE";
"B \NAC \NWC"4;
"S \NAC"
BN"29"131;
%"GND"
"1","(-6625,1350)","0","mstr_symbols","I332";
;
BOM_COST"MEM"
CDS_LIB"mstr_symbols"
SIZE"1B"
VOLTAGE"0.0"
BODY_TYPE"PLUMBING"
HDL_POWER"GND";
"A\NAC"1;
%"Q_RES"
"2","(-6625,1575)","0","pure_quanta","I349";
;
LOCATION"R762"
$SEC"1"
CDS_SEC"1"
WATTAGE"1/16W"
MATERIAL"CHIP"
TOLERANCE"1%"
VALUE"23.2K"
PACK_TYPE"0402LF"
CDS_LIB"pure_quanta"
PART_NUMBER"CS32322FB03";
"A"
$PN"1"29;
"B"
$PN"2"1;
%"SCONN288_DDR506112002KQ"
"1","(-7075,3975)","0","pure_quanta","I350";
;
LOCATION"J17"
$SEC"1"
CDS_SEC"1"
VALUE"SCONN288_DDR506112002KQ"
PART_TYPE"SMLF"
MATERIAL"IO"
CDS_LMAN_SYM_OUTLINE"-450,1900,450,-1850"
NEEDS_NO_SIZE"TRUE"
CDS_LIB"pure_quanta"
PART_NUMBER"DFHST8FS479";
"PWR_GOOD||FAIL_N"
$PN"147"23;
"DQ31_A"
$PN"194"169;
"CB7_A"
$PN"205"168;
"CB4_A"
$PN"58"167;
"CB1_A"
$PN"53"166;
"CB7_B"
$PN"236"165;
"ALERT_N \B"
$PN"62"14;
"CA0_A"
$PN"66"164;
"CA0_B"
$PN"76"163;
"CA1_A"
$PN"211"162;
"CA1_B"
$PN"221"161;
"CA2_A"
$PN"68"160;
"CA2_B"
$PN"78"159;
"CA3_A"
$PN"213"158;
"CA3_B"
$PN"223"157;
"CA4_A"
$PN"70"156;
"CA4_B"
$PN"80"155;
"CA5_A"
$PN"215"154;
"CA5_B"
$PN"225"153;
"CA6_A"
$PN"72"152;
"CA6_B"
$PN"82"151;
"CB6_A"
$PN"203"150;
"CB5_A"
$PN"60"149;
"CB3_A"
$PN"198"148;
"CB2_A"
$PN"196"147;
"CB0_A"
$PN"51"146;
"CB6_B"
$PN"234"145;
"CB5_B"
$PN"91"144;
"CB4_B"
$PN"89"143;
"CB3_B"
$PN"243"142;
"CB2_B"
$PN"241"141;
"CB1_B"
$PN"98"140;
"CB0_B"
$PN"96"139;
"CK_C \B"
$PN"218"138;
"CK_T"
$PN"217"137;
"CS0_A_N"
$PN"64"136;
"CS0_B_N"
$PN"84"135;
"CS1_A_N"
$PN"209"134;
"CS1_B_N"
$PN"229"133;
"DQ30_A"
$PN"192"132;
"DQ29_A"
$PN"49"131;
"DQ28_A"
$PN"47"76;
"DQ27_A"
$PN"187"75;
"DQ26_A"
$PN"185"130;
"DQ25_A"
$PN"42"129;
"DQ24_A"
$PN"40"74;
"DQ23_A"
$PN"183"73;
"DQ22_A"
$PN"181"72;
"DQ21_A"
$PN"38"71;
"DQ20_A"
$PN"36"70;
"DQ19_A"
$PN"176"128;
"DQ18_A"
$PN"174"127;
"DQ17_A"
$PN"31"126;
"DQ16_A"
$PN"29"125;
"DQ15_A"
$PN"172"124;
"DQ14_A"
$PN"170"123;
"DQ13_A"
$PN"27"122;
"DQ12_A"
$PN"25"121;
"DQ11_A"
$PN"165"120;
"DQ10_A"
$PN"163"119;
"DQ9_A"
$PN"20"118;
"DQ8_A"
$PN"18"117;
"DQ7_A"
$PN"161"116;
"DQ6_A"
$PN"159"115;
"DQ5_A"
$PN"16"114;
"DQ4_A"
$PN"14"113;
"DQ3_A"
$PN"154"112;
"DQ2_A"
$PN"152"111;
"DQ1_A"
$PN"9"28;
"DQ0_A"
$PN"7"110;
"DQ31_B"
$PN"287"109;
"DQ30_B"
$PN"285"108;
"DQ29_B"
$PN"142"107;
"DQ28_B"
$PN"140"106;
"DQ27_B"
$PN"280"105;
"DQ26_B"
$PN"278"104;
"DQ25_B"
$PN"135"103;
"DQ24_B"
$PN"133"102;
"DQ23_B"
$PN"276"101;
"DQ22_B"
$PN"274"100;
"DQ21_B"
$PN"131"99;
"DQ20_B"
$PN"129"98;
"DQ19_B"
$PN"269"97;
"DQ18_B"
$PN"267"96;
"DQ17_B"
$PN"124"95;
"DQ16_B"
$PN"122"94;
"DQ15_B"
$PN"265"93;
"DQ14_B"
$PN"263"92;
"DQ13_B"
$PN"120"91;
"DQ12_B"
$PN"118"90;
"DQ11_B"
$PN"258"89;
"DQ10_B"
$PN"256"88;
"DQ9_B"
$PN"113"87;
"DQ8_B"
$PN"111"86;
"DQ7_B"
$PN"254"85;
"DQ6_B"
$PN"252"84;
"DQ5_B"
$PN"109"83;
"DQ4_B"
$PN"107"82;
"DQ3_B"
$PN"247"81;
"DQ2_B"
$PN"245"80;
"DQ1_B"
$PN"102"79;
"DQ0_B"
$PN"100"27;
"HAS"
$PN"148"171;
"HSCL"
$PN"4"22;
"HSDA"
$PN"5"170;
"LBD||RSP_A_N"
$PN"86"25;
"LBS||RSP_B_N"
$PN"87"26;
"PAR_A"
$PN"74"78;
"PAR_B"
$PN"227"77;
"RESET_N \B"
$PN"207"17;
"RFU6"
$PN"232"0;
"RFU5"
$PN"231"0;
"RFU4"
$PN"220"0;
"RFU3"
$PN"150"0;
"RFU2"
$PN"149"0;
"RFU1"
$PN"144"0;
"RFU0"
$PN"2"0;
"VIN_MGMT"
$PN"3"172;
%"SCONN288_DDR506112002KQ"
"3","(-1400,4050)","0","pure_quanta","I352";
;
LOCATION"J17"
$SEC"3"
CDS_SEC"3"
PART_TYPE"SMLF"
VALUE"SCONN288_DDR506112002KQ"
MATERIAL"IO"
CDS_LMAN_SYM_OUTLINE"-450,1800,450,-1750"
NEEDS_NO_SIZE"TRUE"
CDS_LIB"pure_quanta"
PART_NUMBER"DFHST8FS479";
"G3"
$PN"G3"20;
"G2"
$PN"G2"20;
"G1"
$PN"G1"20;
"VSS62"
$PN"141"20;
"VSS61"
$PN"139"20;
"VSS60"
$PN"136"20;
"VSS58"
$PN"132"20;
"VSS104"
$PN"240"21;
"VSS102"
$PN"235"21;
"VSS100"
$PN"230"21;
"VIN_BULK2"
$PN"146"18;
"VIN_BULK1"
$PN"145"18;
"VIN_BULK0"
$PN"1"18;
"VSS126"
$PN"288"21;
"VSS125"
$PN"286"21;
"VSS124"
$PN"284"21;
"VSS123"
$PN"281"21;
"VSS122"
$PN"279"21;
"VSS121"
$PN"277"21;
"VSS120"
$PN"275"21;
"VSS119"
$PN"273"21;
"VSS118"
$PN"270"21;
"VSS117"
$PN"268"21;
"VSS116"
$PN"266"21;
"VSS115"
$PN"264"21;
"VSS114"
$PN"262"21;
"VSS113"
$PN"259"21;
"VSS112"
$PN"257"21;
"VSS111"
$PN"255"21;
"VSS110"
$PN"253"21;
"VSS109"
$PN"251"21;
"VSS108"
$PN"248"21;
"VSS107"
$PN"246"21;
"VSS106"
$PN"244"21;
"VSS105"
$PN"242"21;
"VSS103"
$PN"237"21;
"VSS101"
$PN"233"21;
"VSS99"
$PN"228"21;
"VSS98"
$PN"226"21;
"VSS97"
$PN"224"21;
"VSS96"
$PN"222"21;
"VSS95"
$PN"219"21;
"VSS94"
$PN"216"21;
"VSS93"
$PN"214"21;
"VSS92"
$PN"212"21;
"VSS91"
$PN"210"21;
"VSS90"
$PN"208"21;
"VSS89"
$PN"206"21;
"VSS88"
$PN"204"21;
"VSS87"
$PN"202"21;
"VSS86"
$PN"199"21;
"VSS85"
$PN"197"21;
"VSS84"
$PN"195"21;
"VSS83"
$PN"193"21;
"VSS82"
$PN"191"21;
"VSS81"
$PN"188"21;
"VSS80"
$PN"186"21;
"VSS79"
$PN"184"21;
"VSS78"
$PN"182"21;
"VSS77"
$PN"180"21;
"VSS76"
$PN"177"21;
"VSS75"
$PN"175"21;
"VSS74"
$PN"173"21;
"VSS73"
$PN"171"21;
"VSS72"
$PN"169"21;
"VSS71"
$PN"166"21;
"VSS70"
$PN"164"21;
"VSS69"
$PN"162"21;
"VSS68"
$PN"160"21;
"VSS67"
$PN"158"21;
"VSS66"
$PN"155"21;
"VSS65"
$PN"153"21;
"VSS64"
$PN"151"21;
"VSS63"
$PN"143"20;
"VSS59"
$PN"134"20;
"VSS57"
$PN"130"20;
"VSS56"
$PN"128"20;
"VSS55"
$PN"125"20;
"VSS54"
$PN"123"20;
"VSS53"
$PN"121"20;
"VSS52"
$PN"119"20;
"VSS51"
$PN"117"20;
"VSS50"
$PN"114"20;
"VSS49"
$PN"112"20;
"VSS48"
$PN"110"20;
"VSS47"
$PN"108"20;
"VSS46"
$PN"106"20;
"VSS45"
$PN"103"20;
"VSS44"
$PN"101"20;
"VSS43"
$PN"99"20;
"VSS42"
$PN"97"20;
"VSS41"
$PN"95"20;
"VSS40"
$PN"92"20;
"VSS39"
$PN"90"20;
"VSS38"
$PN"88"20;
"VSS37"
$PN"85"20;
"VSS36"
$PN"83"20;
"VSS35"
$PN"81"20;
"VSS34"
$PN"79"20;
"VSS33"
$PN"77"20;
"VSS32"
$PN"75"20;
"VSS31"
$PN"73"20;
"VSS30"
$PN"71"20;
"VSS29"
$PN"69"20;
"VSS28"
$PN"67"20;
"VSS27"
$PN"65"20;
"VSS26"
$PN"63"20;
"VSS25"
$PN"61"20;
"VSS24"
$PN"59"20;
"VSS23"
$PN"57"20;
"VSS22"
$PN"54"20;
"VSS21"
$PN"52"20;
"VSS20"
$PN"50"20;
"VSS19"
$PN"48"20;
"VSS18"
$PN"46"20;
"VSS17"
$PN"43"20;
"VSS16"
$PN"41"20;
"VSS15"
$PN"39"20;
"VSS14"
$PN"37"20;
"VSS13"
$PN"35"20;
"VSS12"
$PN"32"20;
"VSS11"
$PN"30"20;
"VSS10"
$PN"28"20;
"VSS9"
$PN"26"20;
"VSS8"
$PN"24"20;
"VSS7"
$PN"21"20;
"VSS6"
$PN"19"20;
"VSS5"
$PN"17"20;
"VSS4"
$PN"15"20;
"VSS3"
$PN"13"20;
"VSS2"
$PN"10"20;
"VSS1"
$PN"8"20;
"VSS0"
$PN"6"20;
%"GND"
"1","(-8925,3300)","0","mstr_symbols","I361";
;
BOM_COST"MEM"
SIZE"1B"
CDS_LIB"mstr_symbols"
VOLTAGE"0"
ROOM"MEM_EFGH_DECOUPLING_CAPS"
BODY_TYPE"PLUMBING"
HDL_POWER"GND";
"A\NAC"2;
%"Q_CAP"
"1","(-8925,3525)","2","pure_quanta","I362";
;
LOCATION"C96"
$SEC"1"
CDS_SEC"1"
MATERIAL"X7R"
TOLERANCE"10%"
VALUE"0.1UF"
PACK_TYPE"0402"
VOLTAGE"25V"
CDS_LIB"pure_quanta"
BOM_COST"MEM"
ROOM""
PART_NUMBER"CH4104K1B00";
"B"
$PN"2"2;
"A"
$PN"1"172;
%"Q_RES"
"1","(-8675,2475)","2","pure_quanta","I364";
;
LOCATION"R293"
$SEC"1"
CDS_SEC"1"
VALUE"1K"
TOLERANCE"1%"
BOM_COST"MEM"
CDS_LIB"pure_quanta"
WATTAGE"1/16W"
MATERIAL"CHIP"
PACK_TYPE"0402LF"
ROOM""
PART_NUMBER"CS21002FB06";
"B"
$PN"2"24;
"A"
$PN"1"23;
%"Q_RES"
"2","(-8550,2625)","0","pure_quanta","I365";
;
LOCATION"R91"
$SEC"1"
CDS_SEC"1"
TOLERANCE"1%"
PACK_TYPE"0402LF"
VALUE"1K"
WATTAGE"1/16W"
MATERIAL"EMPTY"
CDS_LIB"pure_quanta"
BOM_COST"MEM"
ROOM""
PART_NUMBER"CS21002FB06";
"A"
$PN"1"3;
"B"
$PN"2"23;
%"VCC_CORE"
"1","(-8550,2800)","0","mstr_symbols","I366";
;
HDL_POWER"P3V3"
CDS_LIB"mstr_symbols"
VOLTAGE"3.3"
ROOM"PVCCINFAON_CPU0_CTRL";
"A"3;
%"TAP"
"1","(-3525,4900)","0","mstr_standard","I371";
;
CDS_LIB"mstr_standard"
BODY_TYPE"PLUMBING"
HDL_TAP"TRUE";
"B \NAC \NWC"10;
"S \NAC"
BN"9"33;
%"TAP"
"1","(-3525,4700)","0","mstr_standard","I372";
;
CDS_LIB"mstr_standard"
BODY_TYPE"PLUMBING"
HDL_TAP"TRUE";
"B \NAC \NWC"10;
"S \NAC"
BN"7"69;
%"TAP"
"1","(-3525,4800)","0","mstr_standard","I373";
;
CDS_LIB"mstr_standard"
BODY_TYPE"PLUMBING"
HDL_TAP"TRUE";
"B \NAC \NWC"10;
"S \NAC"
BN"8"35;
%"TAP"
"1","(-3525,4600)","0","mstr_standard","I374";
;
CDS_LIB"mstr_standard"
BODY_TYPE"PLUMBING"
HDL_TAP"TRUE";
"B \NAC \NWC"10;
"S \NAC"
BN"6"40;
%"TAP"
"1","(-3525,4500)","0","mstr_standard","I375";
;
CDS_LIB"mstr_standard"
BODY_TYPE"PLUMBING"
HDL_TAP"TRUE";
"B \NAC \NWC"10;
"S \NAC"
BN"5"44;
%"TAP"
"1","(-3525,4400)","0","mstr_standard","I376";
;
CDS_LIB"mstr_standard"
BODY_TYPE"PLUMBING"
HDL_TAP"TRUE";
"B \NAC \NWC"10;
"S \NAC"
BN"4"48;
%"TAP"
"1","(-3525,4300)","0","mstr_standard","I377";
;
CDS_LIB"mstr_standard"
BODY_TYPE"PLUMBING"
HDL_TAP"TRUE";
"B \NAC \NWC"10;
"S \NAC"
BN"3"52;
%"TAP"
"1","(-3525,4200)","0","mstr_standard","I378";
;
CDS_LIB"mstr_standard"
BODY_TYPE"PLUMBING"
HDL_TAP"TRUE";
"B \NAC \NWC"10;
"S \NAC"
BN"2"56;
%"TAP"
"1","(-3525,4100)","0","mstr_standard","I379";
;
CDS_LIB"mstr_standard"
BODY_TYPE"PLUMBING"
HDL_TAP"TRUE";
"B \NAC \NWC"10;
"S \NAC"
BN"1"60;
%"TAP"
"1","(-3525,4000)","0","mstr_standard","I380";
;
CDS_LIB"mstr_standard"
BODY_TYPE"PLUMBING"
HDL_TAP"TRUE";
"B \NAC \NWC"10;
"S \NAC"
BN"0"64;
%"TAP"
"1","(-3525,3850)","0","mstr_standard","I381";
;
CDS_LIB"mstr_standard"
BODY_TYPE"PLUMBING"
HDL_TAP"TRUE";
"B \NAC \NWC"13;
"S \NAC"
BN"9"31;
%"TAP"
"1","(-3525,3750)","0","mstr_standard","I382";
;
CDS_LIB"mstr_standard"
BODY_TYPE"PLUMBING"
HDL_TAP"TRUE";
"B \NAC \NWC"13;
"S \NAC"
BN"8"66;
%"TAP"
"1","(-3525,3550)","0","mstr_standard","I383";
;
CDS_LIB"mstr_standard"
BODY_TYPE"PLUMBING"
HDL_TAP"TRUE";
"B \NAC \NWC"13;
"S \NAC"
BN"6"39;
%"TAP"
"1","(-3525,3650)","0","mstr_standard","I384";
;
CDS_LIB"mstr_standard"
BODY_TYPE"PLUMBING"
HDL_TAP"TRUE";
"B \NAC \NWC"13;
"S \NAC"
BN"7"36;
%"TAP"
"1","(-3525,3450)","0","mstr_standard","I385";
;
CDS_LIB"mstr_standard"
BODY_TYPE"PLUMBING"
HDL_TAP"TRUE";
"B \NAC \NWC"13;
"S \NAC"
BN"5"42;
%"TAP"
"1","(-3525,3350)","0","mstr_standard","I386";
;
CDS_LIB"mstr_standard"
BODY_TYPE"PLUMBING"
HDL_TAP"TRUE";
"B \NAC \NWC"13;
"S \NAC"
BN"4"46;
%"TAP"
"1","(-3525,3150)","0","mstr_standard","I387";
;
CDS_LIB"mstr_standard"
BODY_TYPE"PLUMBING"
HDL_TAP"TRUE";
"B \NAC \NWC"13;
"S \NAC"
BN"2"54;
%"TAP"
"1","(-3525,3250)","0","mstr_standard","I388";
;
CDS_LIB"mstr_standard"
BODY_TYPE"PLUMBING"
HDL_TAP"TRUE";
"B \NAC \NWC"13;
"S \NAC"
BN"3"50;
%"TAP"
"1","(-3525,3050)","0","mstr_standard","I389";
;
CDS_LIB"mstr_standard"
BODY_TYPE"PLUMBING"
HDL_TAP"TRUE";
"B \NAC \NWC"13;
"S \NAC"
BN"1"58;
%"TAP"
"1","(-3525,2950)","0","mstr_standard","I390";
;
CDS_LIB"mstr_standard"
BODY_TYPE"PLUMBING"
HDL_TAP"TRUE";
"B \NAC \NWC"13;
"S \NAC"
BN"0"62;
%"TAP"
"1","(-3725,4950)","0","mstr_standard","I391";
;
CDS_LIB"mstr_standard"
BODY_TYPE"PLUMBING"
HDL_TAP"TRUE";
"B \NAC \NWC"11;
"S \NAC"
BN"9"32;
%"TAP"
"1","(-3725,4850)","0","mstr_standard","I392";
;
CDS_LIB"mstr_standard"
BODY_TYPE"PLUMBING"
HDL_TAP"TRUE";
"B \NAC \NWC"11;
"S \NAC"
BN"8"34;
%"TAP"
"1","(-3725,4750)","0","mstr_standard","I393";
;
CDS_LIB"mstr_standard"
BODY_TYPE"PLUMBING"
HDL_TAP"TRUE";
"B \NAC \NWC"11;
"S \NAC"
BN"7"37;
%"TAP"
"1","(-3725,4550)","0","mstr_standard","I394";
;
CDS_LIB"mstr_standard"
BODY_TYPE"PLUMBING"
HDL_TAP"TRUE";
"B \NAC \NWC"11;
"S \NAC"
BN"5"43;
%"TAP"
"1","(-3725,4650)","0","mstr_standard","I395";
;
CDS_LIB"mstr_standard"
BODY_TYPE"PLUMBING"
HDL_TAP"TRUE";
"B \NAC \NWC"11;
"S \NAC"
BN"6"68;
%"TAP"
"1","(-3725,4450)","0","mstr_standard","I396";
;
CDS_LIB"mstr_standard"
BODY_TYPE"PLUMBING"
HDL_TAP"TRUE";
"B \NAC \NWC"11;
"S \NAC"
BN"4"47;
%"TAP"
"1","(-3725,4350)","0","mstr_standard","I397";
;
CDS_LIB"mstr_standard"
BODY_TYPE"PLUMBING"
HDL_TAP"TRUE";
"B \NAC \NWC"11;
"S \NAC"
BN"3"51;
%"TAP"
"1","(-3725,4250)","0","mstr_standard","I398";
;
CDS_LIB"mstr_standard"
BODY_TYPE"PLUMBING"
HDL_TAP"TRUE";
"B \NAC \NWC"11;
"S \NAC"
BN"2"55;
%"TAP"
"1","(-3725,4050)","0","mstr_standard","I399";
;
CDS_LIB"mstr_standard"
BODY_TYPE"PLUMBING"
HDL_TAP"TRUE";
"B \NAC \NWC"11;
"S \NAC"
BN"0"63;
%"TAP"
"1","(-3725,4150)","0","mstr_standard","I400";
;
CDS_LIB"mstr_standard"
BODY_TYPE"PLUMBING"
HDL_TAP"TRUE";
"B \NAC \NWC"11;
"S \NAC"
BN"1"59;
%"TAP"
"1","(-3725,3800)","0","mstr_standard","I401";
;
CDS_LIB"mstr_standard"
BODY_TYPE"PLUMBING"
HDL_TAP"TRUE";
"B \NAC \NWC"12;
"S \NAC"
BN"8"67;
%"TAP"
"1","(-3725,3900)","0","mstr_standard","I402";
;
CDS_LIB"mstr_standard"
BODY_TYPE"PLUMBING"
HDL_TAP"TRUE";
"B \NAC \NWC"12;
"S \NAC"
BN"9"30;
%"TAP"
"1","(-3725,3700)","0","mstr_standard","I403";
;
CDS_LIB"mstr_standard"
BODY_TYPE"PLUMBING"
HDL_TAP"TRUE";
"B \NAC \NWC"12;
"S \NAC"
BN"7"65;
%"TAP"
"1","(-3725,3600)","0","mstr_standard","I404";
;
CDS_LIB"mstr_standard"
BODY_TYPE"PLUMBING"
HDL_TAP"TRUE";
"B \NAC \NWC"12;
"S \NAC"
BN"6"38;
%"TAP"
"1","(-3725,3500)","0","mstr_standard","I405";
;
CDS_LIB"mstr_standard"
BODY_TYPE"PLUMBING"
HDL_TAP"TRUE";
"B \NAC \NWC"12;
"S \NAC"
BN"5"41;
%"TAP"
"1","(-3725,3400)","0","mstr_standard","I406";
;
CDS_LIB"mstr_standard"
BODY_TYPE"PLUMBING"
HDL_TAP"TRUE";
"B \NAC \NWC"12;
"S \NAC"
BN"4"45;
%"TAP"
"1","(-3725,3300)","0","mstr_standard","I407";
;
CDS_LIB"mstr_standard"
BODY_TYPE"PLUMBING"
HDL_TAP"TRUE";
"B \NAC \NWC"12;
"S \NAC"
BN"3"49;
%"TAP"
"1","(-3725,3200)","0","mstr_standard","I408";
;
CDS_LIB"mstr_standard"
BODY_TYPE"PLUMBING"
HDL_TAP"TRUE";
"B \NAC \NWC"12;
"S \NAC"
BN"2"53;
%"TAP"
"1","(-3725,3100)","0","mstr_standard","I409";
;
CDS_LIB"mstr_standard"
BODY_TYPE"PLUMBING"
HDL_TAP"TRUE";
"B \NAC \NWC"12;
"S \NAC"
BN"1"57;
%"TAP"
"1","(-3725,3000)","0","mstr_standard","I410";
;
CDS_LIB"mstr_standard"
BODY_TYPE"PLUMBING"
HDL_TAP"TRUE";
"B \NAC \NWC"12;
"S \NAC"
BN"0"61;
%"SCONN288_DDR506112002KQ"
"2","(-4675,3950)","0","pure_quanta","I411";
;
LOCATION"J17"
$SEC"2"
CDS_SEC"2"
MATERIAL"IO"
PART_TYPE"SMLF"
VALUE"SCONN288_DDR506112002KQ"
CDS_LMAN_SYM_OUTLINE"-600,1150,600,-1150"
NEEDS_NO_SIZE"TRUE"
CDS_LIB"pure_quanta"
PART_NUMBER"DFHST8FS479";
"DQS7_A_C||TDQS7_A_C \B"
$PN"178"69;
"DQS6_A_T||TDQS6_A_T"
$PN"168"68;
"DQS8_B_T||TDQS8_B_T"
$PN"283"67;
"DQS8_B_C||TDQS8_B_C \B"
$PN"282"66;
"DQS7_B_T||TDQS7_B_T"
$PN"272"65;
"DQS0_A_C \B"
$PN"12"64;
"DQS0_A_T"
$PN"11"63;
"DQS0_B_C \B"
$PN"105"62;
"DQS0_B_T"
$PN"104"61;
"DQS1_A_C \B"
$PN"23"60;
"DQS1_A_T"
$PN"22"59;
"DQS1_B_C \B"
$PN"116"58;
"DQS1_B_T"
$PN"115"57;
"DQS2_A_C \B"
$PN"34"56;
"DQS2_A_T"
$PN"33"55;
"DQS2_B_C \B"
$PN"127"54;
"DQS2_B_T"
$PN"126"53;
"DQS3_A_C \B"
$PN"45"52;
"DQS3_A_T"
$PN"44"51;
"DQS3_B_C \B"
$PN"138"50;
"DQS3_B_T"
$PN"137"49;
"DQS4_A_C \B"
$PN"56"48;
"DQS4_A_T"
$PN"55"47;
"DQS4_B_C \B"
$PN"238"46;
"DQS4_B_T"
$PN"239"45;
"DQS5_A_C||TDQS5_A_C||DQS5_A_T||TDQS5_A_T \B"
$PN"156"44;
"DQS5_A_T||TDQS5_A_T"
$PN"157"43;
"DQS5_B_C||TDQS5_B_C \B"
$PN"249"42;
"DQS5_B_T||TDQS5_B_T"
$PN"250"41;
"DQS6_A_C||TDQS6_A_C||DQS6_A_T||TDQS6_A_T \B"
$PN"167"40;
"DQS6_B_C||TDQS6_B_C \B"
$PN"260"39;
"DQS6_B_T||TDQS6_B_T"
$PN"261"38;
"DQS7_A_T||TDQS7_A_T"
$PN"179"37;
"DQS7_B_C||TDQS7_B_C \B"
$PN"271"36;
"DQS8_A_C||TDQS8_A_C \B"
$PN"189"35;
"DQS8_A_T||TDQS8_A_T"
$PN"190"34;
"DQS9_A_C||TDQS9_A_C \B"
$PN"200"33;
"DQS9_A_T||TDQS9_A_T"
$PN"201"32;
"DQS9_B_C||TDQS9_B_C \B"
$PN"94"31;
"DQS9_B_T||TDQS9_B_T||DBI4_B_N"
$PN"93"30;
%"GND"
"1","(-3000,5800)","0","pure_quanta_power","I412";
;
CDS_LIB"pure_quanta_power"
BOM_COST"MEM"
SIZE"1B"
ROOM"MEM_EFGH_DECOUPLING_CAPS"
HDL_POWER"GND";
"A<SIZE-1..0>\NAC"19;
%"Q_CAP"
"1","(-3000,6150)","2","pure_quanta","I413";
;
LOCATION"C146"
$SEC"1"
CDS_SEC"1"
VOLTAGE"25V"
PACK_TYPE"C0805"
VALUE"10UF"
TOLERANCE"10%"
MATERIAL"X6S"
CDS_LIB"pure_quanta"
BOM_COST"MEM"
ROOM""
PART_NUMBER"CH6104KEA00";
"B"
$PN"2"19;
"A"
$PN"1"18;
%"Q_CAP"
"1","(-2425,6150)","2","pure_quanta","I414";
;
LOCATION"C147"
$SEC"1"
CDS_SEC"1"
PACK_TYPE"C0805"
VOLTAGE"25V"
VALUE"10UF"
TOLERANCE"10%"
MATERIAL"X6S"
CDS_LIB"pure_quanta"
BOM_COST"MEM"
ROOM""
PART_NUMBER"CH6104KEA00";
"B"
$PN"2"19;
"A"
$PN"1"18;
%"UNIVERSAL_POWER"
"1","(-3000,6475)","0","pure_quanta_power","I415";
;
HDL_POWER"P12V_MEM_CPU0"
BOM_COST"VR_SYSTEM"
CDS_LIB"pure_quanta_power";
"A"18;
%"Q_RES"
"1","(-7950,2950)","0","pure_quanta","I417";
;
LOCATION"R1570"
$SEC"1"
CDS_SEC"1"
VALUE"49.9"
CDS_LIB"pure_quanta"
MATERIAL"CHIP"
PACK_TYPE"0402LF"
WATTAGE"1/16W"
TOLERANCE"1%"
PART_NUMBER"CS04992FB07";
"B"
$PN"2"22;
"A"
$PN"1"16;
%"Q_RES"
"1","(-8275,3175)","0","pure_quanta","I418";
;
LOCATION"R1677"
$SEC"1"
CDS_SEC"1"
PACK_TYPE"0402LF"
MATERIAL"CHIP"
VALUE"10"
CDS_LIB"pure_quanta"
TOLERANCE"1%"
WATTAGE"1/16W"
PART_NUMBER"CS01002FB07";
"B"
$PN"2"170;
"A"
$PN"1"15;
END.
